(kicad_pcb
	(version 20241229)
	(generator "pcbnew")
	(generator_version "9.0")
	(general
		(thickness 1.6296)
		(legacy_teardrops no)
	)
	(paper "A3")
	(title_block
		(title "Thunderbolt to 10GbE adapter")
		(date "2026-04-21")
		(rev "1.1.0")
		(company "Antmicro Ltd")
		(comment 1 "www.antmicro.com")
		(comment 9 "footprints 459-463 of 703")
	)
	(layers
		(0 "F.Cu" signal)
		(4 "In1.Cu" signal)
		(6 "In2.Cu" signal)
		(8 "In3.Cu" signal)
		(10 "In4.Cu" signal)
		(12 "In5.Cu" signal)
		(14 "In6.Cu" signal)
		(2 "B.Cu" signal)
		(9 "F.Adhes" user "F.Adhesive")
		(11 "B.Adhes" user "B.Adhesive")
		(13 "F.Paste" user)
		(15 "B.Paste" user)
		(5 "F.SilkS" user "F.Silkscreen")
		(7 "B.SilkS" user "B.Silkscreen")
		(1 "F.Mask" user)
		(3 "B.Mask" user)
		(17 "Dwgs.User" user "User.Drawings")
		(19 "Cmts.User" user "User.Comments")
		(21 "Eco1.User" user "User.Eco1")
		(23 "Eco2.User" user "User.Eco2")
		(25 "Edge.Cuts" user)
		(27 "Margin" user)
		(31 "F.CrtYd" user "F.Courtyard")
		(29 "B.CrtYd" user "B.Courtyard")
		(35 "F.Fab" user)
		(33 "B.Fab" user)
	)
	(footprint "antmicro-footprints:R_0402_1005Metric"
		(layer "B.Cu")
		(at 180.8 71.5)
		(descr "Resistor SMD 0402")
		(tags "resistor SMD 0402")
		(property "Reference" "R84"
			(at 3 0.4 180)
			(layer "B.SilkS")
			(effects
				(font
					(size 0.7 0.7)
					(thickness 0.15)
				)
				(justify left bottom mirror)
			)
		)
		(property "Value" "R_330R_0402"
			(at -1.011843 -1.772047 180)
			(layer "B.Fab")
			(effects
				(font
					(size 0.7 0.7)
					(thickness 0.15)
				)
				(justify left bottom mirror)
			)
		)
		(property "Datasheet" "https://www.bourns.com/docs/product-datasheets/cr.pdf"
			(at 0 0 180)
			(layer "B.Fab")
			(hide yes)
			(effects
				(font
					(size 1.27 1.27)
					(thickness 0.15)
				)
				(justify mirror)
			)
		)
		(property "Description" "SMD Chip Resistor, 330 ohm, ± 1%, 62.5 mW, 0402 [1005 Metric], Thick Film, General Purpose"
			(at 0 0 180)
			(layer "B.Fab")
			(hide yes)
			(effects
				(font
					(size 1.27 1.27)
					(thickness 0.15)
				)
				(justify mirror)
			)
		)
		(property "MPN" "CR0402-FX-3300GLF"
			(at 0 0 0)
			(unlocked yes)
			(layer "B.Fab")
			(hide yes)
			(effects
				(font
					(size 1 1)
					(thickness 0.15)
				)
				(justify mirror)
			)
		)
		(property "Manufacturer" "Bourns"
			(at 0 0 0)
			(unlocked yes)
			(layer "B.Fab")
			(hide yes)
			(effects
				(font
					(size 1 1)
					(thickness 0.15)
				)
				(justify mirror)
			)
		)
		(property "License" "Apache-2.0"
			(at 0 0 0)
			(unlocked yes)
			(layer "B.Fab")
			(hide yes)
			(effects
				(font
					(size 1 1)
					(thickness 0.15)
				)
				(justify mirror)
			)
		)
		(property "Author" "Antmicro"
			(at 0 0 0)
			(unlocked yes)
			(layer "B.Fab")
			(hide yes)
			(effects
				(font
					(size 1 1)
					(thickness 0.15)
				)
				(justify mirror)
			)
		)
		(property "Val" "330R"
			(at 0 0 0)
			(unlocked yes)
			(layer "B.Fab")
			(hide yes)
			(effects
				(font
					(size 1 1)
					(thickness 0.15)
				)
				(justify mirror)
			)
		)
		(property "Tolerance" "1%"
			(at 0 0 0)
			(unlocked yes)
			(layer "B.Fab")
			(hide yes)
			(effects
				(font
					(size 1 1)
					(thickness 0.15)
				)
				(justify mirror)
			)
		)
		(sheetname "/X710 DCDC converters/")
		(sheetfile "DCDC_converters_X710.kicad_sch")
		(attr smd)
		(fp_rect
			(start -0.925 0.47)
			(end 0.925 -0.47)
			(stroke
				(width 0.05)
				(type default)
			)
			(fill no)
			(layer "B.CrtYd")
		)
		(fp_rect
			(start -0.5 0.25)
			(end 0.5 -0.25)
			(stroke
				(width 0.15)
				(type solid)
			)
			(fill no)
			(layer "B.Fab")
		)
		(fp_text user "Author: Antmicro"
			(at -0.95 -4.169 180)
			(layer "B.Fab")
			(effects
				(font
					(size 0.7 0.7)
					(thickness 0.15)
				)
				(justify left bottom mirror)
			)
		)
		(fp_text user "${REFERENCE}"
			(at -0.95 -3.168 180)
			(layer "B.Fab")
			(effects
				(font
					(size 0.7 0.7)
					(thickness 0.15)
				)
				(justify left bottom mirror)
			)
		)
		(fp_text user "License: Apache-2.0"
			(at -0.95 -5.169 180)
			(layer "B.Fab")
			(effects
				(font
					(size 0.7 0.7)
					(thickness 0.15)
				)
				(justify left bottom mirror)
			)
		)
		(pad "1" smd roundrect
			(at -0.48 0)
			(size 0.59 0.64)
			(layers "B.Cu" "B.Mask" "B.Paste")
			(roundrect_rratio 0.25)
			(net 428 "Net-(Q2-C)")
			(pintype "passive")
		)
		(pad "2" smd roundrect
			(at 0.48 0)
			(size 0.59 0.64)
			(layers "B.Cu" "B.Mask" "B.Paste")
			(roundrect_rratio 0.25)
			(net 415 "Net-(D7-C)")
			(pintype "passive")
		)
	)
	(footprint "antmicro-footprints:SOT-416"
		(layer "B.Cu")
		(at 178.5 68 -90)
		(descr "SOT-416")
		(tags "SOT-416")
		(property "Reference" "Q2"
			(at -0.75 1.3 90)
			(layer "B.SilkS")
			(effects
				(font
					(size 0.7 0.7)
					(thickness 0.15)
				)
				(justify left bottom mirror)
			)
		)
		(property "Value" "DTC014T_SOT-416"
			(at 0 -2 90)
			(layer "B.Fab")
			(effects
				(font
					(size 0.7 0.7)
					(thickness 0.15)
				)
				(justify left bottom mirror)
			)
		)
		(property "Datasheet" "https://www.rohm.com/datasheet?p=DTC014TEB&dist=Mouser&media=referral&source=mouser.com&campaign=Mouser"
			(at 0 0 90)
			(layer "B.Fab")
			(hide yes)
			(effects
				(font
					(size 1.27 1.27)
					(thickness 0.15)
				)
				(justify mirror)
			)
		)
		(property "Description" "Bipolar (BJT) Single Transistor with built-in base resistor, NPN, 50V, 100mA, 150mW, SOT-416FL, Surface Mount"
			(at 0 0 90)
			(layer "B.Fab")
			(hide yes)
			(effects
				(font
					(size 1.27 1.27)
					(thickness 0.15)
				)
				(justify mirror)
			)
		)
		(property "Manufacturer" "ROHM Semiconductor"
			(at 0 0 270)
			(unlocked yes)
			(layer "B.Fab")
			(hide yes)
			(effects
				(font
					(size 1 1)
					(thickness 0.15)
				)
				(justify mirror)
			)
		)
		(property "MPN" "DTC014TEBTL"
			(at 0 0 270)
			(unlocked yes)
			(layer "B.Fab")
			(hide yes)
			(effects
				(font
					(size 1 1)
					(thickness 0.15)
				)
				(justify mirror)
			)
		)
		(property "Author" "Antmicro"
			(at 0 0 270)
			(unlocked yes)
			(layer "B.Fab")
			(hide yes)
			(effects
				(font
					(size 1 1)
					(thickness 0.15)
				)
				(justify mirror)
			)
		)
		(property "License" "Apache-2.0"
			(at 0 0 270)
			(unlocked yes)
			(layer "B.Fab")
			(hide yes)
			(effects
				(font
					(size 1 1)
					(thickness 0.15)
				)
				(justify mirror)
			)
		)
		(sheetname "/X710 DCDC converters/")
		(sheetfile "DCDC_converters_X710.kicad_sch")
		(attr smd)
		(fp_line
			(start 0.508 0.9)
			(end -0.5 0.9)
			(stroke
				(width 0.15)
				(type solid)
			)
			(layer "B.SilkS")
		)
		(fp_line
			(start 0.508 0.9)
			(end 0.508 0.592)
			(stroke
				(width 0.15)
				(type solid)
			)
			(layer "B.SilkS")
		)
		(fp_line
			(start -0.5 0.15)
			(end -0.5 -0.15)
			(stroke
				(width 0.15)
				(type solid)
			)
			(layer "B.SilkS")
		)
		(fp_line
			(start 0.5 -0.9)
			(end 0.5 -0.7)
			(stroke
				(width 0.15)
				(type solid)
			)
			(layer "B.SilkS")
		)
		(fp_line
			(start 0.5 -0.9)
			(end -0.5 -0.9)
			(stroke
				(width 0.15)
				(type solid)
			)
			(layer "B.SilkS")
		)
		(fp_rect
			(start -1 1.05)
			(end 1 -1.05)
			(stroke
				(width 0.05)
				(type solid)
			)
			(fill no)
			(layer "B.CrtYd")
		)
		(fp_line
			(start -0.05 0.9)
			(end -0.45 0.5)
			(stroke
				(width 0.15)
				(type solid)
			)
			(layer "B.Fab")
		)
		(fp_rect
			(start 0.45 -0.9)
			(end -0.45 0.9)
			(stroke
				(width 0.15)
				(type solid)
			)
			(fill no)
			(layer "B.Fab")
		)
		(fp_text user "Author: Antmicro"
			(at -1 -4.602 90)
			(layer "B.Fab")
			(effects
				(font
					(size 0.7 0.7)
					(thickness 0.15)
				)
				(justify left bottom mirror)
			)
		)
		(fp_text user "${REFERENCE}"
			(at -1 -3.4 90)
			(layer "B.Fab")
			(effects
				(font
					(size 0.7 0.7)
					(thickness 0.15)
				)
				(justify left bottom mirror)
			)
		)
		(fp_text user "License: Apache-2.0"
			(at -1 -5.802 90)
			(layer "B.Fab")
			(effects
				(font
					(size 0.7 0.7)
					(thickness 0.15)
				)
				(justify left bottom mirror)
			)
		)
		(pad "1" smd rect
			(at -0.652 0.5 270)
			(size 0.6 0.5)
			(layers "B.Cu" "B.Mask" "B.Paste")
			(net 335 "/X710 DCDC converters/+VCCD_OUT")
			(pinfunction "B")
			(pintype "input")
		)
		(pad "2" smd rect
			(at -0.652 -0.498 270)
			(size 0.6 0.5)
			(layers "B.Cu" "B.Mask" "B.Paste")
			(net 23 "GND")
			(pinfunction "E")
			(pintype "passive")
		)
		(pad "3" smd rect
			(at 0.65 0 270)
			(size 0.6 0.5)
			(layers "B.Cu" "B.Mask" "B.Paste")
			(net 428 "Net-(Q2-C)")
			(pinfunction "C")
			(pintype "passive")
		)
	)
	(footprint "antmicro-footprints:R_0402_1005Metric"
		(layer "B.Cu")
		(at 119.5 89.75 90)
		(descr "Resistor SMD 0402")
		(tags "resistor SMD 0402")
		(property "Reference" "R77"
			(at -5.85 0.3 270)
			(layer "B.SilkS")
			(effects
				(font
					(size 0.7 0.7)
					(thickness 0.15)
				)
				(justify left bottom mirror)
			)
		)
		(property "Value" "R_1k_0402"
			(at -1.011843 -1.772047 270)
			(layer "B.Fab")
			(effects
				(font
					(size 0.7 0.7)
					(thickness 0.15)
				)
				(justify left bottom mirror)
			)
		)
		(property "Datasheet" "https://www.bourns.com/docs/product-datasheets/cr.pdf"
			(at 0 0 270)
			(layer "B.Fab")
			(hide yes)
			(effects
				(font
					(size 1.27 1.27)
					(thickness 0.15)
				)
				(justify mirror)
			)
		)
		(property "Description" "SMD Chip Resistor, 1 kohm, ± 1%, 63 mW, 0402 [1005 Metric], Thick Film, General Purpose"
			(at 0 0 270)
			(layer "B.Fab")
			(hide yes)
			(effects
				(font
					(size 1.27 1.27)
					(thickness 0.15)
				)
				(justify mirror)
			)
		)
		(property "MPN" "CR0402-FX-1001GLF"
			(at 0 0 90)
			(unlocked yes)
			(layer "B.Fab")
			(hide yes)
			(effects
				(font
					(size 1 1)
					(thickness 0.15)
				)
				(justify mirror)
			)
		)
		(property "Manufacturer" "Bourns"
			(at 0 0 90)
			(unlocked yes)
			(layer "B.Fab")
			(hide yes)
			(effects
				(font
					(size 1 1)
					(thickness 0.15)
				)
				(justify mirror)
			)
		)
		(property "License" "Apache-2.0"
			(at 0 0 90)
			(unlocked yes)
			(layer "B.Fab")
			(hide yes)
			(effects
				(font
					(size 1 1)
					(thickness 0.15)
				)
				(justify mirror)
			)
		)
		(property "Author" "Antmicro"
			(at 0 0 90)
			(unlocked yes)
			(layer "B.Fab")
			(hide yes)
			(effects
				(font
					(size 1 1)
					(thickness 0.15)
				)
				(justify mirror)
			)
		)
		(property "Val" "1k"
			(at 0 0 90)
			(unlocked yes)
			(layer "B.Fab")
			(hide yes)
			(effects
				(font
					(size 1 1)
					(thickness 0.15)
				)
				(justify mirror)
			)
		)
		(property "Tolerance" "1%"
			(at 0 0 90)
			(unlocked yes)
			(layer "B.Fab")
			(hide yes)
			(effects
				(font
					(size 1 1)
					(thickness 0.15)
				)
				(justify mirror)
			)
		)
		(sheetname "/TB Controller - Power/")
		(sheetfile "tb-power.kicad_sch")
		(attr smd)
		(fp_rect
			(start -0.925 0.47)
			(end 0.925 -0.47)
			(stroke
				(width 0.05)
				(type default)
			)
			(fill no)
			(layer "B.CrtYd")
		)
		(fp_rect
			(start -0.5 0.25)
			(end 0.5 -0.25)
			(stroke
				(width 0.15)
				(type solid)
			)
			(fill no)
			(layer "B.Fab")
		)
		(fp_text user "Author: Antmicro"
			(at -0.95 -4.169 270)
			(layer "B.Fab")
			(effects
				(font
					(size 0.7 0.7)
					(thickness 0.15)
				)
				(justify left bottom mirror)
			)
		)
		(fp_text user "${REFERENCE}"
			(at -0.95 -3.168 270)
			(layer "B.Fab")
			(effects
				(font
					(size 0.7 0.7)
					(thickness 0.15)
				)
				(justify left bottom mirror)
			)
		)
		(fp_text user "License: Apache-2.0"
			(at -0.95 -5.169 270)
			(layer "B.Fab")
			(effects
				(font
					(size 0.7 0.7)
					(thickness 0.15)
				)
				(justify left bottom mirror)
			)
		)
		(pad "1" smd roundrect
			(at -0.48 0 90)
			(size 0.59 0.64)
			(layers "B.Cu" "B.Mask" "B.Paste")
			(roundrect_rratio 0.25)
			(net 436 "Net-(R77-Pad1)")
			(pintype "passive")
		)
		(pad "2" smd roundrect
			(at 0.48 0 90)
			(size 0.59 0.64)
			(layers "B.Cu" "B.Mask" "B.Paste")
			(roundrect_rratio 0.25)
			(net 68 "/TB Controller - Power/VCC_0P9")
			(pintype "passive")
		)
	)
	(footprint "antmicro-footprints:C_0402_1005Metric"
		(layer "B.Cu")
		(at 154.9 105 90)
		(descr "Capacitor SMD 0402")
		(tags "capacitor SMD 0402")
		(property "Reference" "C151"
			(at 1.4 -0.6 270)
			(layer "B.SilkS")
			(effects
				(font
					(size 0.7 0.7)
					(thickness 0.15)
				)
				(justify left bottom mirror)
			)
		)
		(property "Value" "C_100n_0402"
			(at -1.022927 -2.155213 270)
			(layer "B.Fab")
			(effects
				(font
					(size 0.7 0.7)
					(thickness 0.15)
				)
				(justify left bottom mirror)
			)
		)
		(property "Datasheet" "https://www.murata.com/products/productdetail?partno=GRM155R61H104KE14%23"
			(at 0 0 270)
			(layer "B.Fab")
			(hide yes)
			(effects
				(font
					(size 1.27 1.27)
					(thickness 0.15)
				)
				(justify mirror)
			)
		)
		(property "Description" "SMD Multilayer Ceramic Capacitor, 0.1 µF, 50 V, 0402 [1005 Metric], ± 10%, X5R, GRM Series"
			(at 0 0 270)
			(layer "B.Fab")
			(hide yes)
			(effects
				(font
					(size 1.27 1.27)
					(thickness 0.15)
				)
				(justify mirror)
			)
		)
		(property "MPN" "GRM155R61H104KE14D"
			(at 0 0 90)
			(unlocked yes)
			(layer "B.Fab")
			(hide yes)
			(effects
				(font
					(size 1 1)
					(thickness 0.15)
				)
				(justify mirror)
			)
		)
		(property "Manufacturer" "Murata"
			(at 0 0 90)
			(unlocked yes)
			(layer "B.Fab")
			(hide yes)
			(effects
				(font
					(size 1 1)
					(thickness 0.15)
				)
				(justify mirror)
			)
		)
		(property "License" "Apache-2.0"
			(at 0 0 90)
			(unlocked yes)
			(layer "B.Fab")
			(hide yes)
			(effects
				(font
					(size 1 1)
					(thickness 0.15)
				)
				(justify mirror)
			)
		)
		(property "Author" "Antmicro"
			(at 0 0 90)
			(unlocked yes)
			(layer "B.Fab")
			(hide yes)
			(effects
				(font
					(size 1 1)
					(thickness 0.15)
				)
				(justify mirror)
			)
		)
		(property "Val" "100n"
			(at 0 0 90)
			(unlocked yes)
			(layer "B.Fab")
			(hide yes)
			(effects
				(font
					(size 1 1)
					(thickness 0.15)
				)
				(justify mirror)
			)
		)
		(property "Voltage" "50V"
			(at 0 0 90)
			(unlocked yes)
			(layer "B.Fab")
			(hide yes)
			(effects
				(font
					(size 1 1)
					(thickness 0.15)
				)
				(justify mirror)
			)
		)
		(property "Dielectric" "X5R"
			(at 0 0 90)
			(unlocked yes)
			(layer "B.Fab")
			(hide yes)
			(effects
				(font
					(size 1 1)
					(thickness 0.15)
				)
				(justify mirror)
			)
		)
		(sheetname "/X710 DCDC converters/")
		(sheetfile "DCDC_converters_X710.kicad_sch")
		(attr smd)
		(fp_rect
			(start -0.925 0.47)
			(end 0.925 -0.47)
			(stroke
				(width 0.05)
				(type default)
			)
			(fill no)
			(layer "B.CrtYd")
		)
		(fp_line
			(start 0.504 -0.248)
			(end -0.494 -0.248)
			(stroke
				(width 0.15)
				(type solid)
			)
			(layer "B.Fab")
		)
		(fp_line
			(start -0.494 -0.248)
			(end -0.494 0.25)
			(stroke
				(width 0.15)
				(type solid)
			)
			(layer "B.Fab")
		)
		(fp_line
			(start 0.504 0.25)
			(end 0.504 -0.248)
			(stroke
				(width 0.15)
				(type solid)
			)
			(layer "B.Fab")
		)
		(fp_line
			(start -0.494 0.25)
			(end 0.504 0.25)
			(stroke
				(width 0.15)
				(type solid)
			)
			(layer "B.Fab")
		)
		(fp_text user "License: Apache-2.0"
			(at -0.939 -5.799 270)
			(layer "B.Fab")
			(effects
				(font
					(size 0.7 0.7)
					(thickness 0.15)
				)
				(justify left bottom mirror)
			)
		)
		(fp_text user "Author: Antmicro"
			(at -0.939 -3.399 270)
			(layer "B.Fab")
			(effects
				(font
					(size 0.7 0.7)
					(thickness 0.15)
				)
				(justify left bottom mirror)
			)
		)
		(fp_text user "${REFERENCE}"
			(at -0.939 -4.599 270)
			(layer "B.Fab")
			(effects
				(font
					(size 0.7 0.7)
					(thickness 0.15)
				)
				(justify left bottom mirror)
			)
		)
		(pad "1" smd roundrect
			(at -0.48 0 90)
			(size 0.59 0.64)
			(layers "B.Cu" "B.Mask" "B.Paste")
			(roundrect_rratio 0.25)
			(net 23 "GND")
			(pintype "passive")
		)
		(pad "2" smd roundrect
			(at 0.48 0 90)
			(size 0.59 0.64)
			(layers "B.Cu" "B.Mask" "B.Paste")
			(roundrect_rratio 0.25)
			(net 338 "/X710 DCDC converters/+1V88_OUT")
			(pintype "passive")
		)
	)
	(footprint "antmicro-footprints:C_0402_1005Metric"
		(layer "B.Cu")
		(at 160.05 133.25 180)
		(descr "Capacitor SMD 0402")
		(tags "capacitor SMD 0402")
		(property "Reference" "C300"
			(at -1.45 -1.35 0)
			(layer "B.SilkS")
			(effects
				(font
					(size 0.7 0.7)
					(thickness 0.15)
				)
				(justify left bottom mirror)
			)
		)
		(property "Value" "C_1u_25V_0402"
			(at -1.022927 -2.155213 0)
			(layer "B.Fab")
			(effects
				(font
					(size 0.7 0.7)
					(thickness 0.15)
				)
				(justify left bottom mirror)
			)
		)
		(property "Datasheet" "https://www.murata.com/products/productdetail?partno=GRM155R61E105KE11%23"
			(at 0 0 0)
			(layer "B.Fab")
			(hide yes)
			(effects
				(font
					(size 1.27 1.27)
					(thickness 0.15)
				)
				(justify mirror)
			)
		)
		(property "Description" "SMD Multilayer Ceramic Capacitor, 1 µF, 25 V, 0402 [1005 Metric], ± 10%, X5R, GRM Series"
			(at 0 0 0)
			(layer "B.Fab")
			(hide yes)
			(effects
				(font
					(size 1.27 1.27)
					(thickness 0.15)
				)
				(justify mirror)
			)
		)
		(property "MPN" "GRM155R61E105KE11J"
			(at 0 0 180)
			(unlocked yes)
			(layer "B.Fab")
			(hide yes)
			(effects
				(font
					(size 1 1)
					(thickness 0.15)
				)
				(justify mirror)
			)
		)
		(property "Manufacturer" "Murata"
			(at 0 0 180)
			(unlocked yes)
			(layer "B.Fab")
			(hide yes)
			(effects
				(font
					(size 1 1)
					(thickness 0.15)
				)
				(justify mirror)
			)
		)
		(property "License" "Apache-2.0"
			(at 0 0 180)
			(unlocked yes)
			(layer "B.Fab")
			(hide yes)
			(effects
				(font
					(size 1 1)
					(thickness 0.15)
				)
				(justify mirror)
			)
		)
		(property "Author" "Antmicro"
			(at 0 0 180)
			(unlocked yes)
			(layer "B.Fab")
			(hide yes)
			(effects
				(font
					(size 1 1)
					(thickness 0.15)
				)
				(justify mirror)
			)
		)
		(property "Val" "1u"
			(at 0 0 180)
			(unlocked yes)
			(layer "B.Fab")
			(hide yes)
			(effects
				(font
					(size 1 1)
					(thickness 0.15)
				)
				(justify mirror)
			)
		)
		(property "Voltage" "25V"
			(at 0 0 180)
			(unlocked yes)
			(layer "B.Fab")
			(hide yes)
			(effects
				(font
					(size 1 1)
					(thickness 0.15)
				)
				(justify mirror)
			)
		)
		(property "Dielectric" "X5R"
			(at 0 0 180)
			(unlocked yes)
			(layer "B.Fab")
			(hide yes)
			(effects
				(font
					(size 1 1)
					(thickness 0.15)
				)
				(justify mirror)
			)
		)
		(sheetname "/2xRJ45/")
		(sheetfile "2xrj45.kicad_sch")
		(attr smd)
		(fp_rect
			(start -0.925 0.47)
			(end 0.925 -0.47)
			(stroke
				(width 0.05)
				(type default)
			)
			(fill no)
			(layer "B.CrtYd")
		)
		(fp_line
			(start 0.504 0.25)
			(end 0.504 -0.248)
			(stroke
				(width 0.15)
				(type solid)
			)
			(layer "B.Fab")
		)
		(fp_line
			(start 0.504 -0.248)
			(end -0.494 -0.248)
			(stroke
				(width 0.15)
				(type solid)
			)
			(layer "B.Fab")
		)
		(fp_line
			(start -0.494 0.25)
			(end 0.504 0.25)
			(stroke
				(width 0.15)
				(type solid)
			)
			(layer "B.Fab")
		)
		(fp_line
			(start -0.494 -0.248)
			(end -0.494 0.25)
			(stroke
				(width 0.15)
				(type solid)
			)
			(layer "B.Fab")
		)
		(fp_text user "Author: Antmicro"
			(at -0.939 -3.399 0)
			(layer "B.Fab")
			(effects
				(font
					(size 0.7 0.7)
					(thickness 0.15)
				)
				(justify left bottom mirror)
			)
		)
		(fp_text user "${REFERENCE}"
			(at -0.939 -4.599 0)
			(layer "B.Fab")
			(effects
				(font
					(size 0.7 0.7)
					(thickness 0.15)
				)
				(justify left bottom mirror)
			)
		)
		(fp_text user "License: Apache-2.0"
			(at -0.939 -5.799 0)
			(layer "B.Fab")
			(effects
				(font
					(size 0.7 0.7)
					(thickness 0.15)
				)
				(justify left bottom mirror)
			)
		)
		(pad "1" smd roundrect
			(at -0.48 0 180)
			(size 0.59 0.64)
			(layers "B.Cu" "B.Mask" "B.Paste")
			(roundrect_rratio 0.25)
			(net 23 "GND")
			(pintype "passive")
		)
		(pad "2" smd roundrect
			(at 0.48 0 180)
			(size 0.59 0.64)
			(layers "B.Cu" "B.Mask" "B.Paste")
			(roundrect_rratio 0.25)
			(net 133 "/2xRJ45/P0_CT")
			(pintype "passive")
		)
	)
)
